# S9S_MB_2U (Grand Teton) — schematic netlist excerpt (pin names and nets, part order shuffled) for the footprints in the layout excerpt that follows; sources: Cadence DE-HDL packaged netlist, KiCad conversion of 03242023_DA0F0TMBIJ0_F0T_Motherboard_J_brd_V01_OCP.brd

C1289  Q_CAP  1UF 25V 10% X6S  pkg C0402  page 134 : A = P3V3_AUX ; B = GND
R2844  Q_RES  33.2 1% CHIP  pkg 0402LF  page 213 : A = FM_SWB_BIC_READY_ISO_N ; B = FM_SWB_BIC_READY_ISO_R_N

(kicad_pcb
	(version 20260206)
	(generator "pcbnew")
	(generator_version "10.0")
	(general
		(thickness 1.6)
		(legacy_teardrops no)
	)
	(paper "A4")
	(title_block
		(title "03242023_DA0F0TMBIJ0_F0T_Motherboard_J_brd_V01_OCP.brd")
		(comment 1 "Grand Teton / footprints 3999-4000 of 6105")
	)
	(layers
		(0 "F.Cu" signal "TOP")
		(4 "In1.Cu" signal "GND")
		(6 "In2.Cu" signal "IN1")
		(8 "In3.Cu" signal "GND1")
		(10 "In4.Cu" signal "IN2")
		(12 "In5.Cu" signal "GND2")
		(14 "In6.Cu" signal "IN3")
		(16 "In7.Cu" signal "GND3")
		(18 "In8.Cu" signal "VCC")
		(20 "In9.Cu" signal "VCC1")
		(22 "In10.Cu" signal "GND4")
		(24 "In11.Cu" signal "IN4")
		(26 "In12.Cu" signal "GND5")
		(28 "In13.Cu" signal "IN5")
		(30 "In14.Cu" signal "GND6")
		(32 "In15.Cu" signal "IN6")
		(34 "In16.Cu" signal "GND7")
		(2 "B.Cu" signal "BOTTOM")
		(9 "F.Adhes" user "F.Adhesive")
		(11 "B.Adhes" user "B.Adhesive")
		(13 "F.Paste" user "Package Geometry/Pastemask Top")
		(15 "B.Paste" user "Package Geometry/Pastemask Bottom")
		(5 "F.SilkS" user "Ref Des/Silkscreen Top")
		(7 "B.SilkS" user "Ref Des/Silkscreen Bottom")
		(1 "F.Mask" user "Board Geometry/Soldermask Top")
		(3 "B.Mask" user "Board Geometry/Soldermask Bottom")
		(17 "Dwgs.User" user "User.Drawings")
		(19 "Cmts.User" user "User.Comments")
		(21 "Eco1.User" user "User.Eco1")
		(23 "Eco2.User" user "User.Eco2")
		(25 "Edge.Cuts" user "Board Geometry/Outline")
		(27 "Margin" user)
		(31 "F.CrtYd" user "Package Geometry/Place Bound Top")
		(29 "B.CrtYd" user "Package Geometry/Place Bound Bottom")
		(35 "F.Fab" user "Ref Des/Assembly Top")
		(33 "B.Fab" user "Ref Des/Assembly Bottom")
	)
	(footprint ""
		(layer "F.Cu")
		(at 164.64788 -105.755948)
		(property "Reference" "R2844"
			(at 0 0 0)
			(layer "F.SilkS")
			(hide yes)
			(effects
				(font
					(size 1.27 1.27)
				)
			)
		)
		(property "Value" ""
			(at 0 0 0)
			(layer "F.Fab")
			(effects
				(font
					(size 1.27 1.27)
				)
			)
		)
		(duplicate_pad_numbers_are_jumpers no)
		(fp_line
			(start -0.7874 -0.4064)
			(end 0.7874 -0.4064)
			(stroke
				(width 0.1524)
				(type default)
			)
			(layer "F.SilkS")
		)
		(fp_line
			(start -0.7874 0.4064)
			(end -0.7874 -0.4064)
			(stroke
				(width 0.1524)
				(type default)
			)
			(layer "F.SilkS")
		)
		(fp_line
			(start 0.7874 -0.4064)
			(end 0.7874 0.4064)
			(stroke
				(width 0.1524)
				(type default)
			)
			(layer "F.SilkS")
		)
		(fp_line
			(start 0.7874 0.4064)
			(end -0.7874 0.4064)
			(stroke
				(width 0.1524)
				(type default)
			)
			(layer "F.SilkS")
		)
		(fp_line
			(start -0.67945 -0.305054)
			(end -0.12065 -0.305054)
			(stroke
				(width 0.1)
				(type default)
			)
			(layer "F.Fab")
		)
		(fp_line
			(start -0.67945 0.3048)
			(end -0.67945 -0.305054)
			(stroke
				(width 0.1)
				(type default)
			)
			(layer "F.Fab")
		)
		(fp_line
			(start -0.12065 -0.305054)
			(end -0.12065 -0.2794)
			(stroke
				(width 0.1)
				(type default)
			)
			(layer "F.Fab")
		)
		(fp_line
			(start -0.12065 -0.2794)
			(end 0.12065 -0.2794)
			(stroke
				(width 0.1)
				(type default)
			)
			(layer "F.Fab")
		)
		(fp_line
			(start -0.12065 0.2794)
			(end -0.12065 0.3048)
			(stroke
				(width 0.1)
				(type default)
			)
			(layer "F.Fab")
		)
		(fp_line
			(start -0.12065 0.3048)
			(end -0.67945 0.3048)
			(stroke
				(width 0.1)
				(type default)
			)
			(layer "F.Fab")
		)
		(fp_line
			(start 0.120396 0.2794)
			(end -0.12065 0.2794)
			(stroke
				(width 0.1)
				(type default)
			)
			(layer "F.Fab")
		)
		(fp_line
			(start 0.120396 0.3048)
			(end 0.120396 0.2794)
			(stroke
				(width 0.1)
				(type default)
			)
			(layer "F.Fab")
		)
		(fp_line
			(start 0.12065 -0.3048)
			(end 0.67945 -0.3048)
			(stroke
				(width 0.1)
				(type default)
			)
			(layer "F.Fab")
		)
		(fp_line
			(start 0.12065 -0.2794)
			(end 0.12065 -0.3048)
			(stroke
				(width 0.1)
				(type default)
			)
			(layer "F.Fab")
		)
		(fp_line
			(start 0.67945 -0.3048)
			(end 0.67945 0.3048)
			(stroke
				(width 0.1)
				(type default)
			)
			(layer "F.Fab")
		)
		(fp_line
			(start 0.67945 0.3048)
			(end 0.120396 0.3048)
			(stroke
				(width 0.1)
				(type default)
			)
			(layer "F.Fab")
		)
		(pad "1" smd circle
			(at -0.40005 0)
			(size 0 0)
			(layers "F.Cu" "F.Mask" "F.Paste")
			(net "FM_SWB_BIC_READY_ISO_N")
		)
		(pad "2" smd circle
			(at 0.40005 0)
			(size 0 0)
			(layers "F.Cu" "F.Mask" "F.Paste")
			(net "FM_SWB_BIC_READY_ISO_R_N")
		)
	)
	(footprint ""
		(layer "F.Cu")
		(at 108.05668 -59.070748)
		(property "Reference" "C1289"
			(at 0 0 0)
			(layer "F.SilkS")
			(hide yes)
			(effects
				(font
					(size 1.27 1.27)
				)
			)
		)
		(property "Value" ""
			(at 0 0 0)
			(layer "F.Fab")
			(effects
				(font
					(size 1.27 1.27)
				)
			)
		)
		(duplicate_pad_numbers_are_jumpers no)
		(fp_line
			(start -0.7874 -0.4064)
			(end 0.7874 -0.4064)
			(stroke
				(width 0.1524)
				(type default)
			)
			(layer "F.SilkS")
		)
		(fp_line
			(start -0.7874 0.4064)
			(end -0.7874 -0.4064)
			(stroke
				(width 0.1524)
				(type default)
			)
			(layer "F.SilkS")
		)
		(fp_line
			(start 0.7874 -0.4064)
			(end 0.7874 0.4064)
			(stroke
				(width 0.1524)
				(type default)
			)
			(layer "F.SilkS")
		)
		(fp_line
			(start 0.7874 0.4064)
			(end -0.7874 0.4064)
			(stroke
				(width 0.1524)
				(type default)
			)
			(layer "F.SilkS")
		)
		(fp_line
			(start -0.67945 -0.305054)
			(end -0.12065 -0.305054)
			(stroke
				(width 0.1)
				(type default)
			)
			(layer "F.Fab")
		)
		(fp_line
			(start -0.67945 0.3048)
			(end -0.67945 -0.305054)
			(stroke
				(width 0.1)
				(type default)
			)
			(layer "F.Fab")
		)
		(fp_line
			(start -0.12065 -0.305054)
			(end -0.12065 -0.2794)
			(stroke
				(width 0.1)
				(type default)
			)
			(layer "F.Fab")
		)
		(fp_line
			(start -0.12065 -0.2794)
			(end 0.12065 -0.2794)
			(stroke
				(width 0.1)
				(type default)
			)
			(layer "F.Fab")
		)
		(fp_line
			(start -0.12065 0.2794)
			(end -0.12065 0.3048)
			(stroke
				(width 0.1)
				(type default)
			)
			(layer "F.Fab")
		)
		(fp_line
			(start -0.12065 0.3048)
			(end -0.67945 0.3048)
			(stroke
				(width 0.1)
				(type default)
			)
			(layer "F.Fab")
		)
		(fp_line
			(start 0.120396 0.2794)
			(end -0.12065 0.2794)
			(stroke
				(width 0.1)
				(type default)
			)
			(layer "F.Fab")
		)
		(fp_line
			(start 0.120396 0.3048)
			(end 0.120396 0.2794)
			(stroke
				(width 0.1)
				(type default)
			)
			(layer "F.Fab")
		)
		(fp_line
			(start 0.12065 -0.3048)
			(end 0.67945 -0.3048)
			(stroke
				(width 0.1)
				(type default)
			)
			(layer "F.Fab")
		)
		(fp_line
			(start 0.12065 -0.2794)
			(end 0.12065 -0.3048)
			(stroke
				(width 0.1)
				(type default)
			)
			(layer "F.Fab")
		)
		(fp_line
			(start 0.67945 -0.3048)
			(end 0.67945 0.3048)
			(stroke
				(width 0.1)
				(type default)
			)
			(layer "F.Fab")
		)
		(fp_line
			(start 0.67945 0.3048)
			(end 0.120396 0.3048)
			(stroke
				(width 0.1)
				(type default)
			)
			(layer "F.Fab")
		)
		(pad "1" smd circle
			(at -0.40005 0)
			(size 0 0)
			(layers "F.Cu" "F.Mask" "F.Paste")
			(net "P3V3_AUX")
		)
		(pad "2" smd circle
			(at 0.40005 0)
			(size 0 0)
			(layers "F.Cu" "F.Mask" "F.Paste")
			(net "GND")
		)
	)
)
